FILE_TYPE = CONNECTIVITY;
{Allegro Design Entry HDL 17.4-2019 S026 (4007227) 1/17/2022}
"PAGE_NUMBER" = 81;
0"NC";
1"FM_CPU1_BMC_RST_R_N";
2"IRQ_CPU_BMC_NMI_N";
3"CPU0_XTRIG_L5";
4"CPU0_XTRIG_L4";
5"IRQ_SMI_ACTIVE_N";
6"IRQ_TPM_SPI_R_N";
7"FM_BMC_TPM_PRES_N";
8"FM_CPU0_XTRIG_L7";
9"FM_BMC_READY_R_N";
10"CPU0_XTRIG_L7";
11"FM_CPU1_BMC_RST_N";
12"FM_BMC_READY_N";
13"PVDDCR_CPU0_P0_OCP_N";
14"PVDDCR_CPU1_P0_OCP_N";
15"CPU1_CORETYPE2";
16"FM_PVDDCR_CPU1_P0_EN";
17"FM_LED_PWRGD_PVDDCR_CPU1_P0";
18"CPU1_SP5R2";
19"CPU1_SP5R1";
20"CPU1_CORETYPE1";
21"CPU0_SP5R2";
22"CPU0_SP5R1";
23"CPU1_CORETYPE0";
24"PVDDCR_CPU1_P1_OCP_N";
25"IRQ_TPM_SPI_R1_N";
26"IRQ_SMI_ACTIVE_N_R";
27"FM_CPU0_XTRIG_L4";
28"FM_CPU0_XTRIG_L5";
29"IRQ_CPU_BMC_NMI_R_N";
30"FM_CPU1_XTRIG_L7";
31"FM_SMM_CRASHDUMP";
32"P3V3_AUX\g";
33"GND\g";
34"P3V3_AUX\g"VOLTAGE"3.3"VOLTAGE"3.3"VOLTAGE"3.3"VOLTAGE"3.3"VOLTAGE"3.3"VOLTAGE"3.3";
35"P1V8_AUX\g";
36"P3V3_AUX\g";
37"P1V8_AUX\g";
38"FM_PRSNT_CPU0_R_N";
39"PVDD11_S3_P1_PMALERT";
40"CLR_CMOS";
41"FM_SMB_RST_E1S_0_N";
42"CPU0_CORETYPE0";
43"FM_OCP_SFF_PWR_GOOD";
44"OCP_V3_2_P3V3_P12V_ADC_R_ALERT";
45"OCP_V3_2_P3V3_P12V_ADC_ALERT";
46"FM_CLR_CMOS";
47"PWRGD_OCP_SFF_PWR_GOOD";
48"FM_CPU0_CORETYPE0";
49"FM_CPU0_CORETYPE2";
50"OCP_SFF_MAIN_PWR_EN";
51"CPU0_CORETYPE2";
52"PVDDCR_CPU0_P1_PMALERT";
53"FM_PLD_OCP_SFF_MAIN_PWR_EN_R";
54"FM_CLKREQ_M2_1_N";
55"FM_PLD_OCP_SFF_AUX_PWR_R_EN";
56"FM_PLD_OCP_SFF_AUX_PWR_EN";
57"M2_SSD0_CLKREQ_EN_N";
58"M2_0_P3V3_ADC_ALERT";
59"CPU0_CORETYPE1";
60"PVDD11_S3_P0_PMALERT";
61"P12V_SCM_ADC_ALERT";
62"FM_SEC_MUX_SEL";
63"FM_SEC_MUX_OE_N";
64"E1S_0_P3V3_P12V_ADC_ALERT";
65"P12V_HSC_T_CRIT_R_N";
66"E1S_0_P3V3_P12V_ADC_R_ALERT";
67"PVDDCR_CPU1_P1_SMB_ALERT";
68"LED_HDD_ACTIVITY_B_PLD_N";
69"PVDDCR_CPU1_P0_SMB_ALERT";
70"P12V_HSC_TEMP_ALERT_R_N";
71"FM_SEC_MUX_R_SEL";
72"FM_SEC_MUX_OE_R_N";
73"FM_SCM_PRSNT1_N";
74"FM_THERMAL_ALERT_R_N";
75"SMB_BMC_GPU_EN";
76"E1S_0_PRSNT_R_N";
77"PWRGD_P5V_AUX_R3";
78"PWRGD_CHAF_CPU0_R2";
79"P12V_OCP_V3_1_PWRGD";
80"PVDD11_S3_P0_EN";
81"FAB_BMC_REV_ID2";
82"FM_PRSNT_CPU1_R_N";
83"FM_PVDDCR_CPU1_P1_R_EN";
84"FM_PRSNT_CPU1_N";
85"FM_CPU0_SP5R4";
86"FAB_BMC_REV_ID1";
87"FM_PVDDCR_CPU1_P1_EN";
88"E1S_0_PRSNT_N";
89"FM_PVDDCR_CPU1_P0_OCP_N";
90"FM_PVDDCR_CPU1_P1_OCP_N";
91"FM_PDB_BUF_EN_N";
92"PWRGD_CHGL_CPU1_R2";
93"CPU1_SP5R3";
94"CPU1_SP5R4";
95"FM_CPU1_SP5R4";
96"FM_PDB_BUF_EN_R_N";
97"PWRGD_CHAF_CPU1_R2";
98"FM_CPU1_CORETYPE0";
99"FM_CPU0_SP5R2";
100"FM_CPU0_SP5R1";
101"FM_APML_MUX2_OE_R_N";
102"CPU1_XTRIG_L6";
103"CPU1_XTRIG_L5";
104"CPU1_SA1";
105"CPU1_XTRIG_L7";
106"FM_PVDDCR_CPU0_P1_OCP_N";
107"FM_CPU1_PROCHOT_R_N";
108"FM_INT_CPU0_HP_UBM_R_N";
109"FM_CPU0_PROCHOT_R_N";
110"FM_CPU0_SA1";
111"CPU0_XTRIG_L6";
112"IRQ_BMC_SMI_N";
113"CPU0_SA1";
114"PWRGD_PVDDCR_CPU1_P0";
115"FM_CPU1_XTRIG_L4";
116"FM_CPU1_XTRIG_L5";
117"FM_CPU0_XTRIG_L6";
118"CPU0_SP5R3";
119"FM_APML_MUX2_OE_N";
120"FM_APML_MUX2_SEL";
121"FM_PWRGD_PVDDCR_CPU1_P0";
122"FM_CPU0_SP5R3";
123"FM_CPU1_CORETYPE2";
124"FM_PVDDCR_CPU1_P0_R_EN";
125"FM_CPU1_CORETYPE1";
126"FM_CPU0_CORETYPE1";
127"FM_APML_MUX2_SEL_R";
128"FM_CPU1_SP5R1";
129"FM_CPU1_SP5R2";
130"FM_SMM_CRASHDUMP_R";
131"FM_BMC_TPM_PRES_N_R";
132"FM_PVDDCR_CPU0_P0_OCP_N";
133"IRQ_BMC_SMI_R_N";
134"FM_CPU1_SA1";
135"FM_CPU1_XTRIG_L6";
136"CPU1_XTRIG_L4";
137"FM_CPU1_SP5R3";
138"FAB_BMC_REV_ID0";
139"FM_CPU0_SA0";
140"FM_PVDD11_S3_P0_OCP_N";
141"FM_PVDD11_S3_P1_OCP_N";
142"FM_CPU1_SA0";
143"FM_INT_CPU0_HP_UBM_N";
144"PVDDCR_CPU0_P1_OCP_N";
145"CPU1_PROCHOT_N";
146"PVDD11_S3_P1_OCP_N";
147"PVDD11_S3_P0_OCP_N";
148"CPU0_THERMTRIP_R_N";
149"CPU1_THERMTRIP_R_N";
150"CPU0_SA0";
151"CPU0_PROCHOT_N";
152"CPU1_SA0";
153"RT_BOARD_ID_ID0";
154"RT_BOARD_ID_ID1";
155"FM_PRSNT_CPU0_N";
156"CPU0_SP5R4";
157"OCP_SFF_P3V3_P12V_ADC_ALERT";
158"PVDDCR_SOC_P0_EN";
159"P12V_OCP_V3_1_PLD_PWRGD";
160"FM_LED_PWRGD_PVDDCR_SOC_P0";
161"FM_LED_PWRGD_PVDDCR_CPU0_P0";
162"PWRGD_CHGL_CPU0_R2";
163"OCP_SFF_P3V3_P12V_ADC_R_ALERT";
164"PWRGD_PVDDCR_SOC_P0";
165"PWRGD_PVDDCR_CPU0_P0";
166"FM_PVDD11_S3_P0_EN";
%"LCMXO3LF9400C5BG484C"
"6","(-6800,1600)","0","pure_quanta","I1";
;
LOCATION"U18"
SEC"6"
MATERIAL"IC"
PART_TYPE"SMLF"
VALUE"LCMXO3LF-9400C-5BG484C"
CDS_LMAN_SYM_OUTLINE"-250,1350,250,-1350"
NEEDS_NO_SIZE"TRUE"
CDS_LIB"pure_quanta"
SEC_TYPE""
PART_NUMBER"AJ094000T08";
"GND52"
$PN"AB22"33;
"GND51"
$PN"AB1"33;
"GND49"
$PN"Y7"33;
"GND50"
$PN"Y16"33;
"GND48"
$PN"W12"33;
"GND47"
$PN"V21"33;
"GND46"
$PN"V2"33;
"GND45"
$PN"R15"33;
"GND44"
$PN"R8"33;
"GND43"
$PN"P14"33;
"GND42"
$PN"P13"33;
"GND41"
$PN"P12"33;
"GND40"
$PN"P11"33;
"GND39"
$PN"P10"33;
"GND38"
$PN"P9"33;
"GND37"
$PN"N21"33;
"GND36"
$PN"N14"33;
"GND35"
$PN"N9"33;
"GND34"
$PN"M14"33;
"GND33"
$PN"M13"33;
"GND32"
$PN"M10"33;
"GND31"
$PN"M9"33;
"GND30"
$PN"M4"33;
"GND29"
$PN"L18"33;
"GND28"
$PN"L14"33;
"GND27"
$PN"L13"33;
"GND26"
$PN"L10"33;
"GND25"
$PN"L9"33;
"GND24"
$PN"L2"33;
"GND23"
$PN"K21"33;
"GND22"
$PN"K14"33;
"GND21"
$PN"K9"33;
"GND20"
$PN"J14"33;
"GND19"
$PN"J13"33;
"GND18"
$PN"J12"33;
"GND17"
$PN"J11"33;
"GND16"
$PN"J10"33;
"GND15"
$PN"J9"33;
"GND14"
$PN"H15"33;
"GND13"
$PN"H13"33;
"GND12"
$PN"H10"33;
"GND11"
$PN"H8"33;
"GND10"
$PN"F21"33;
"GND9"
$PN"F2"33;
"GND8"
$PN"E18"33;
"GND7"
$PN"E5"33;
"GND6"
$PN"C11"33;
"GND5"
$PN"C2"33;
"GND4"
$PN"B16"33;
"GND3"
$PN"B7"33;
"GND2"
$PN"A22"33;
"GND1"
$PN"A1"33;
%"Q_RES"
"1","(-3200,4325)","0","pure_quanta","I100";
;
LOCATION"R223"
$SEC"1"
CDS_SEC"1"
VALUE"0"
CDS_LIB"pure_quanta"
BOM_COST"MEM"
WATTAGE"1/16W"
MATERIAL"CHIP"
TOLERANCE"5%"
PACK_TYPE"0402LF"
PART_NUMBER"CS00002JB13";
"B"
$PN"2"156;
"A"
$PN"1"85;
%"Q_RES"
"1","(-3200,4375)","0","pure_quanta","I101";
;
LOCATION"R182"
$SEC"1"
CDS_SEC"1"
VALUE"0"
BOM_COST"MEM"
CDS_LIB"pure_quanta"
WATTAGE"1/16W"
MATERIAL"CHIP"
TOLERANCE"5%"
PACK_TYPE"0402LF"
PART_NUMBER"CS00002JB13";
"B"
$PN"2"155;
"A"
$PN"1"38;
%"Q_RES"
"1","(-3200,4575)","0","pure_quanta","I102";
;
LOCATION"R6051"
$SEC"1"
CDS_SEC"1"
VALUE"0"
BOM_COST"MEM"
CDS_LIB"pure_quanta"
WATTAGE"1/16W"
MATERIAL"CHIP"
TOLERANCE"5%"
PACK_TYPE"0402LF"
PART_NUMBER"CS00002JB13";
"B"
$PN"2"159;
"A"
$PN"1"79;
%"Q_RES"
"1","(-3200,4975)","0","pure_quanta","I103";
;
LOCATION"R227"
$SEC"1"
CDS_SEC"1"
VALUE"33"
BOM_COST"MEM"
CDS_LIB"pure_quanta"
WATTAGE"1/16W"
MATERIAL"CHIP"
TOLERANCE"5%"
PACK_TYPE"0402LF"
PART_NUMBER"CS03302JB10";
"B"
$PN"2"80;
"A"
$PN"1"166;
%"Q_RES"
"1","(-3200,5025)","0","pure_quanta","I104";
;
LOCATION"R271"
$SEC"1"
CDS_SEC"1"
VALUE"0"
BOM_COST"MEM"
WATTAGE"1/16W"
MATERIAL"CHIP"
TOLERANCE"5%"
PACK_TYPE"0402LF"
CDS_LIB"pure_quanta"
PART_NUMBER"CS00002JB13";
"B"
$PN"2"84;
"A"
$PN"1"82;
%"Q_RES"
"1","(-3200,5075)","0","pure_quanta","I105";
;
LOCATION"R285"
$SEC"1"
CDS_SEC"1"
VALUE"33"
CDS_LIB"pure_quanta"
BOM_COST"MEM"
WATTAGE"1/16W"
MATERIAL"CHIP"
TOLERANCE"5%"
PACK_TYPE"0402LF"
PART_NUMBER"CS03302JB10";
"B"
$PN"2"87;
"A"
$PN"1"83;
%"Q_RES"
"1","(-3250,5575)","0","pure_quanta","I106";
;
LOCATION"R81"
$SEC"1"
CDS_SEC"1"
VALUE"33"
CDS_LIB"pure_quanta"
BOM_COST"MEM"
WATTAGE"1/16W"
MATERIAL"CHIP"
TOLERANCE"5%"
PACK_TYPE"0402LF"
PART_NUMBER"CS03302JB10";
"B"
$PN"2"143;
"A"
$PN"1"108;
%"Q_RES"
"1","(-3250,5525)","0","pure_quanta","I107";
;
LOCATION"R221"
$SEC"1"
CDS_SEC"1"
VALUE"33"
BOM_COST"MEM"
WATTAGE"1/16W"
MATERIAL"CHIP"
TOLERANCE"5%"
PACK_TYPE"0402LF"
CDS_LIB"pure_quanta"
PART_NUMBER"CS03302JB10";
"B"
$PN"2"113;
"A"
$PN"1"110;
%"Q_RES"
"1","(-3250,5825)","0","pure_quanta","I108";
;
LOCATION"R266"
$SEC"1"
CDS_SEC"1"
VALUE"33"
PACK_TYPE"0402LF"
TOLERANCE"5%"
MATERIAL"CHIP"
WATTAGE"1/16W"
BOM_COST"MEM"
CDS_LIB"pure_quanta"
PART_NUMBER"CS03302JB10";
"B"
$PN"2"152;
"A"
$PN"1"142;
%"Q_RES"
"1","(-3250,5725)","0","pure_quanta","I109";
;
LOCATION"R220"
$SEC"1"
CDS_SEC"1"
VALUE"33"
BOM_COST"MEM"
WATTAGE"1/16W"
MATERIAL"CHIP"
TOLERANCE"5%"
PACK_TYPE"0402LF"
CDS_LIB"pure_quanta"
PART_NUMBER"CS03302JB10";
"B"
$PN"2"150;
"A"
$PN"1"139;
%"Q_RES"
"1","(-3250,5775)","0","pure_quanta","I110";
;
LOCATION"R179"
$SEC"1"
CDS_SEC"1"
VALUE"33"
BOM_COST"MEM"
CDS_LIB"pure_quanta"
WATTAGE"1/16W"
MATERIAL"CHIP"
TOLERANCE"5%"
PACK_TYPE"0402LF"
PART_NUMBER"CS03302JB10";
"B"
$PN"2"151;
"A"
$PN"1"109;
%"Q_RES"
"1","(-3250,5975)","0","pure_quanta","I111";
;
LOCATION"R226"
$SEC"1"
CDS_SEC"1"
VALUE"0"
CDS_LIB"pure_quanta"
BOM_COST"MEM"
WATTAGE"1/16W"
MATERIAL"CHIP"
TOLERANCE"5%"
PACK_TYPE"0402LF"
PART_NUMBER"CS00002JB13";
"B"
$PN"2"147;
"A"
$PN"1"140;
%"Q_RES"
"1","(-3250,6075)","0","pure_quanta","I112";
;
LOCATION"R270"
$SEC"1"
CDS_SEC"1"
VALUE"33"
BOM_COST"MEM"
CDS_LIB"pure_quanta"
WATTAGE"1/16W"
MATERIAL"CHIP"
TOLERANCE"5%"
PACK_TYPE"0402LF"
PART_NUMBER"CS03302JB10";
"B"
$PN"2"145;
"A"
$PN"1"107;
%"Q_RES"
"1","(-3250,6025)","0","pure_quanta","I113";
;
LOCATION"R278"
$SEC"1"
CDS_SEC"1"
VALUE"0"
CDS_LIB"pure_quanta"
BOM_COST"MEM"
WATTAGE"1/16W"
MATERIAL"CHIP"
TOLERANCE"5%"
PACK_TYPE"0402LF"
PART_NUMBER"CS00002JB13";
"B"
$PN"2"146;
"A"
$PN"1"141;
%"Q_RES"
"1","(-3250,6125)","0","pure_quanta","I140";
;
LOCATION"R284"
$SEC"1"
CDS_SEC"1"
VALUE"0"
BOM_COST"MEM"
CDS_LIB"pure_quanta"
WATTAGE"1/16W"
MATERIAL"CHIP"
TOLERANCE"5%"
PACK_TYPE"0402LF"
PART_NUMBER"CS00002JB13";
"B"
$PN"2"144;
"A"
$PN"1"106;
%"LCMXO3LF9400C5BG484C"
"5","(-2325,1525)","0","pure_quanta","I141";
;
LOCATION"U18"
SEC"5"
MATERIAL"IC"
VALUE"LCMXO3LF-9400C-5BG484C"
PART_TYPE"SMLF"
CDS_LIB"pure_quanta"
NEEDS_NO_SIZE"TRUE"
CDS_LMAN_SYM_OUTLINE"-400,1000,400,-1000"
SEC_TYPE""
PART_NUMBER"AJ094000T08";
"VCCIO0_5"
$PN"G13"36;
"VCCIO0_6"
$PN"H9"36;
"VCCIO0_9"
$PN"H14"36;
"VCCIO0_8"
$PN"H12"36;
"VCCIO0_7"
$PN"H11"36;
"VCCIO0_4"
$PN"G10"36;
"VCCIO0_3"
$PN"C16"36;
"VCCIO0_2"
$PN"C12"36;
"VCCIO0_1"
$PN"C7"36;
"VCCIO1_9"
$PN"V20"37;
"VCCIO1_8"
$PN"P15"37;
"VCCIO1_7"
$PN"N15"37;
"VCCIO1_6"
$PN"M18"37;
"VCCIO1_5"
$PN"M15"37;
"VCCIO1_4"
$PN"L15"37;
"VCCIO1_3"
$PN"K15"37;
"VCCIO1_2"
$PN"J15"37;
"VCCIO1_1"
$PN"F20"37;
"VCCIO2_9"
$PN"W16"34;
"VCCIO2_8"
$PN"W11"34;
"VCCIO2_7"
$PN"W7"34;
"VCCIO2_6"
$PN"R14"34;
"VCCIO2_5"
$PN"R13"34;
"VCCIO2_4"
$PN"R12"34;
"VCCIO2_3"
$PN"R11"34;
"VCCIO2_2"
$PN"R10"34;
"VCCIO2_1"
$PN"R9"34;
"VCCIO3_3"
$PN"V3"34;
"VCCIO3_2"
$PN"P8"34;
"VCCIO3_1"
$PN"N8"34;
"VCCIO4_3"
$PN"M3"34;
"VCCIO4_2"
$PN"M8"34;
"VCCIO4_1"
$PN"L8"34;
"VCCIO5_3"
$PN"K8"35;
"VCCIO5_2"
$PN"J8"35;
"VCCIO5_1"
$PN"F3"35;
"VCC12"
$PN"N13"32;
"VCC11"
$PN"N12"32;
"VCC10"
$PN"N11"32;
"VCC9"
$PN"N10"32;
"VCC8"
$PN"M12"32;
"VCC7"
$PN"M11"32;
"VCC6"
$PN"L12"32;
"VCC5"
$PN"L11"32;
"VCC4"
$PN"K13"32;
"VCC3"
$PN"K12"32;
"VCC2"
$PN"K11"32;
"VCC1"
$PN"K10"32;
%"UNIVERSAL_POWER"
"1","(-3175,2600)","2","pure_quanta_power","I142";
;
HDL_POWER"P3V3_AUX"
CDS_LIB"pure_quanta_power";
"A"32;
%"LCMXO3LF9400C5BG484C"
"1","(-4850,4775)","0","pure_quanta","I143";
;
LOCATION"U18"
SEC"1"
PART_TYPE"SMLF"
VALUE"LCMXO3LF-9400C-5BG484C"
MATERIAL"IC"
CDS_LIB"pure_quanta"
CDS_LMAN_SYM_OUTLINE"-500,1400,500,-1400"
NEEDS_NO_SIZE"TRUE"
SEC_TYPE""
PART_NUMBER"AJ094000T08";
"PL12D"
$PN"K6"81;
"PL12C"
$PN"K7"86;
"PL12B"
$PN"J1"138;
"PL12A"
$PN"J2"110;
"PL11D"
$PN"J3"108;
"PL11C"
$PN"J4"153;
"PL11B"
$PN"J5"149;
"PL11A"
$PN"H5"139;
"PL10D"
$PN"J6"109;
"PL10C"
$PN"J7"142;
"PL10B"
$PN"H1"154;
"PL10A"
$PN"H2"148;
"PL7D"
$PN"H3"140;
"PL7C"
$PN"H4"141;
"PL7B||PCLKC5_0"
$PN"G1"107;
"PL7A||PCLKT5_0"
$PN"G2"106;
"PL30D"
$PN"T7"83;
"PL30C"
$PN"V5"82;
"PL30B"
$PN"W4"166;
"PL30A"
$PN"Y3"165;
"PL29D"
$PN"Y2"164;
"PL29C"
$PN"W3"158;
"PL29B"
$PN"AA1"157;
"PL29A"
$PN"Y1"162;
"PL28D"
$PN"U5"161;
"PL28C"
$PN"V4"160;
"PL28B"
$PN"W2"79;
"PL28A"
$PN"W1"78;
"PL27D"
$PN"U4"77;
"PL27C"
$PN"U3"76;
"PL27B||PCLKC3_0"
$PN"V1"38;
"PL27A||PCLKT3_0"
$PN"U2"85;
"PL19D"
$PN"M7"53;
"PL19C"
$PN"P3"49;
"PL19B"
$PN"R1"48;
"PL19A"
$PN"P2"41;
"PL18D"
$PN"N4"47;
"PL18C"
$PN"N3"46;
"PL18B"
$PN"P1"45;
"PL18A"
$PN"N2"54;
"PL17D"
$PN"M5"52;
"PL17C"
$PN"M6"55;
"PL17B"
$PN"N1"39;
"PL17A"
$PN"M1"58;
"PL26B"
$PN"T4"95;
"PL26A"
$PN"T3"137;
"PL25D"
$PN"R7"121;
"PL25C"
$PN"R6"97;
"PL24D"
$PN"P7"124;
"PL24C"
$PN"R5"17;
"PL24B"
$PN"R4"129;
"PL24A"
$PN"R3"128;
"PL25B"
$PN"U1"122;
"PL25A"
$PN"T2"123;
"PL6B"
$PN"F1"132;
"PL6A"
$PN"E1"131;
"PL6D"
$PN"G4"90;
"PL6C"
$PN"G3"89;
"PL16D"
$PN"L4"75;
"PL16C"
$PN"L3"74;
"PL14D"
$PN"L5"69;
"PL14C"
$PN"L6"67;
"PL26D"
$PN"T6"92;
"PL26C"
$PN"T5"91;
"PL21D"
$PN"P6"101;
"PL21C"
$PN"P5"127;
"PL21B"
$PN"T1"125;
"PL21A"
$PN"R2"126;
"PL20D"
$PN"N7"70;
"PL20C"
$PN"N6"99;
"PL20B"
$PN"N5"100;
"PL20A"
$PN"P4"98;
"PL16B||PCLKC4_0"
$PN"M2"73;
"PL16A||PCLKT4_0"
$PN"L1"68;
"PL14B"
$PN"K1"71;
"PL14A"
$PN"K2"72;
"PL13D"
$PN"K3"64;
"PL13C"
$PN"K4"65;
"PL13B"
$PN"K5"61;
"PL13A"
$PN"L7"60;
"PL5D"
$PN"F4"9;
"PL5C"
$PN"E3"8;
"PL5B"
$PN"E2"1;
"PL5A"
$PN"D1"130;
"PL4D"
$PN"H6"25;
"PL4C"
$PN"G5"26;
"PL4B||L_GPLLC_IN"
$PN"D2"27;
"PL4A||L_GPLLT_IN"
$PN"C1"28;
"PL3D"
$PN"H7"29;
"PL3C"
$PN"G6"30;
"PL3B||L_GPLLC_FB"
$PN"F5"133;
"PL3A||L_GPLLT_FB"
$PN"E4"117;
"PL2D"
$PN"G7"134;
"PL2C"
$PN"F6"135;
"PL2B"
$PN"D4"116;
"PL2A"
$PN"D3"115;
%"Q_RES"
"1","(-6450,5025)","0","pure_quanta","I146";
;
LOCATION"R6073"
$SEC"1"
CDS_SEC"1"
VALUE"0"
PACK_TYPE"0402LF"
TOLERANCE"5%"
MATERIAL"CHIP"
WATTAGE"1/16W"
BOM_COST"MEM"
CDS_LIB"pure_quanta"
PART_NUMBER"CS00002JB13";
"B"
$PN"2"91;
"A"
$PN"1"96;
%"Q_RES"
"1","(-6325,3825)","0","pure_quanta","I164";
;
LOCATION"R6183"
$SEC"1"
CDS_SEC"1"
VALUE"0"
BOM_COST"MEM"
WATTAGE"1/16W"
MATERIAL"CHIP"
TOLERANCE"5%"
PACK_TYPE"0402LF"
CDS_LIB"pure_quanta"
PART_NUMBER"CS00002JB13";
"B"
$PN"2"72;
"A"
$PN"1"63;
%"Q_RES"
"1","(-6325,3775)","0","pure_quanta","I165";
;
LOCATION"R6184"
$SEC"1"
CDS_SEC"1"
VALUE"0"
CDS_LIB"pure_quanta"
PACK_TYPE"0402LF"
TOLERANCE"5%"
MATERIAL"CHIP"
WATTAGE"1/16W"
BOM_COST"MEM"
PART_NUMBER"CS00002JB13";
"B"
$PN"2"71;
"A"
$PN"1"62;
%"Q_RES"
"1","(-6450,4475)","0","pure_quanta","I168";
;
LOCATION"R132"
$SEC"1"
CDS_SEC"1"
VALUE"0"
CDS_LIB"pure_quanta"
PACK_TYPE"0402LF"
TOLERANCE"5%"
MATERIAL"CHIP"
WATTAGE"1/16W"
BOM_COST"MEM"
PART_NUMBER"CS00002JB13";
"B"
$PN"2"101;
"A"
$PN"1"119;
%"Q_RES"
"1","(-6450,4425)","0","pure_quanta","I169";
;
LOCATION"R133"
$SEC"1"
CDS_SEC"1"
VALUE"0"
PACK_TYPE"0402LF"
TOLERANCE"5%"
MATERIAL"CHIP"
WATTAGE"1/16W"
BOM_COST"MEM"
CDS_LIB"pure_quanta"
PART_NUMBER"CS00002JB13";
"B"
$PN"2"127;
"A"
$PN"1"120;
%"Q_RES"
"1","(-3225,4775)","0","pure_quanta","I176";
;
LOCATION"R1340"
$SEC"1"
CDS_SEC"1"
VALUE"0"
CDS_LIB"pure_quanta"
BOM_COST"MEM"
WATTAGE"1/16W"
MATERIAL"CHIP"
TOLERANCE"5%"
PACK_TYPE"0402LF"
PART_NUMBER"CS00002JB13";
"B"
$PN"2"163;
"A"
$PN"1"157;
%"Q_RES"
"1","(-6350,3875)","0","pure_quanta","I178";
;
LOCATION"R1329"
$SEC"1"
CDS_SEC"1"
VALUE"0"
CDS_LIB"pure_quanta"
BOM_COST"MEM"
WATTAGE"1/16W"
MATERIAL"CHIP"
TOLERANCE"5%"
PACK_TYPE"0402LF"
PART_NUMBER"CS00002JB13";
"B"
$PN"2"64;
"A"
$PN"1"66;
%"Q_RES"
"1","(-3275,3775)","2","pure_quanta","I180";
;
LOCATION"R1339"
$SEC"1"
CDS_SEC"1"
VALUE"0"
BOM_COST"MEM"
WATTAGE"1/16W"
MATERIAL"CHIP"
TOLERANCE"5%"
PACK_TYPE"0402LF"
CDS_LIB"pure_quanta"
PART_NUMBER"CS00002JB13";
"B"
$PN"2"45;
"A"
$PN"1"44;
%"GND"
"1","(-6200,250)","0","pure_quanta_power","I2";
;
CDS_LIB"pure_quanta_power"
SIZE"1B"
HDL_POWER"GND";
"A<SIZE-1..0>\NAC"33;
%"Q_RES"
"1","(-6450,4125)","0","pure_quanta","I44";
;
LOCATION"R262"
$SEC"1"
CDS_SEC"1"
VALUE"0"
CDS_LIB"pure_quanta"
PACK_TYPE"0402LF"
TOLERANCE"5%"
MATERIAL"CHIP"
WATTAGE"1/16W"
BOM_COST"MEM"
PART_NUMBER"CS00002JB13";
"B"
$PN"2"98;
"A"
$PN"1"23;
%"Q_RES"
"1","(-6450,4175)","0","pure_quanta","I45";
;
LOCATION"R180"
$SEC"1"
CDS_SEC"1"
VALUE"0"
CDS_LIB"pure_quanta"
BOM_COST"MEM"
WATTAGE"1/16W"
MATERIAL"CHIP"
TOLERANCE"5%"
PACK_TYPE"0402LF"
PART_NUMBER"CS00002JB13";
"B"
$PN"2"100;
"A"
$PN"1"22;
%"Q_RES"
"1","(-6450,4225)","0","pure_quanta","I46";
;
LOCATION"R181"
$SEC"1"
CDS_SEC"1"
VALUE"0"
CDS_LIB"pure_quanta"
BOM_COST"MEM"
WATTAGE"1/16W"
MATERIAL"CHIP"
TOLERANCE"5%"
PACK_TYPE"0402LF"
PART_NUMBER"CS00002JB13";
"B"
$PN"2"99;
"A"
$PN"1"21;
%"Q_RES"
"1","(-6450,4375)","0","pure_quanta","I47";
;
LOCATION"R263"
$SEC"1"
CDS_SEC"1"
VALUE"0"
BOM_COST"MEM"
CDS_LIB"pure_quanta"
WATTAGE"1/16W"
MATERIAL"CHIP"
TOLERANCE"5%"
PACK_TYPE"0402LF"
PART_NUMBER"CS00002JB13";
"B"
$PN"2"125;
"A"
$PN"1"20;
%"Q_RES"
"1","(-6450,4325)","0","pure_quanta","I48";
;
LOCATION"R184"
$SEC"1"
CDS_SEC"1"
VALUE"0"
CDS_LIB"pure_quanta"
BOM_COST"MEM"
WATTAGE"1/16W"
MATERIAL"CHIP"
TOLERANCE"5%"
PACK_TYPE"0402LF"
PART_NUMBER"CS00002JB13";
"B"
$PN"2"126;
"A"
$PN"1"59;
%"Q_RES"
"1","(-6450,4525)","0","pure_quanta","I49";
;
LOCATION"R260"
$SEC"1"
CDS_SEC"1"
VALUE"0"
CDS_LIB"pure_quanta"
BOM_COST"MEM"
WATTAGE"1/16W"
MATERIAL"CHIP"
TOLERANCE"5%"
PACK_TYPE"0402LF"
PART_NUMBER"CS00002JB13";
"B"
$PN"2"128;
"A"
$PN"1"19;
%"Q_RES"
"1","(-6450,4575)","0","pure_quanta","I50";
;
LOCATION"R261"
$SEC"1"
CDS_SEC"1"
VALUE"0"
CDS_LIB"pure_quanta"
BOM_COST"MEM"
WATTAGE"1/16W"
MATERIAL"CHIP"
TOLERANCE"5%"
PACK_TYPE"0402LF"
PART_NUMBER"CS00002JB13";
"B"
$PN"2"129;
"A"
$PN"1"18;
%"Q_RES"
"1","(-6450,4675)","0","pure_quanta","I51";
;
LOCATION"R232"
$SEC"1"
CDS_SEC"1"
VALUE"33"
CDS_LIB"pure_quanta"
BOM_COST"MEM"
WATTAGE"1/16W"
MATERIAL"CHIP"
TOLERANCE"5%"
PACK_TYPE"0402LF"
PART_NUMBER"CS03302JB10";
"B"
$PN"2"124;
"A"
$PN"1"16;
%"Q_RES"
"1","(-6450,4775)","0","pure_quanta","I52";
;
LOCATION"R222"
$SEC"1"
CDS_SEC"1"
VALUE"0"
BOM_COST"MEM"
CDS_LIB"pure_quanta"
WATTAGE"1/16W"
MATERIAL"CHIP"
TOLERANCE"5%"
PACK_TYPE"0402LF"
PART_NUMBER"CS00002JB13";
"B"
$PN"2"122;
"A"
$PN"1"118;
%"Q_RES"
"1","(-6450,4725)","0","pure_quanta","I53";
;
LOCATION"R264"
$SEC"1"
CDS_SEC"1"
VALUE"0"
CDS_LIB"pure_quanta"
BOM_COST"MEM"
WATTAGE"1/16W"
MATERIAL"CHIP"
TOLERANCE"5%"
PACK_TYPE"0402LF"
PART_NUMBER"CS00002JB13";
"B"
$PN"2"123;
"A"
$PN"1"15;
%"Q_RES"
"1","(-6450,4875)","0","pure_quanta","I54";
;
LOCATION"R233"
$SEC"1"
CDS_SEC"1"
VALUE"0"
BOM_COST"MEM"
CDS_LIB"pure_quanta"
WATTAGE"1/16W"
MATERIAL"CHIP"
TOLERANCE"5%"
PACK_TYPE"0402LF"
PART_NUMBER"CS00002JB13";
"B"
$PN"2"121;
"A"
$PN"1"114;
%"Q_RES"
"1","(-6450,4925)","0","pure_quanta","I55";
;
LOCATION"R268"
$SEC"1"
CDS_SEC"1"
VALUE"0"
BOM_COST"MEM"
CDS_LIB"pure_quanta"
WATTAGE"1/16W"
MATERIAL"CHIP"
TOLERANCE"5%"
PACK_TYPE"0402LF"
PART_NUMBER"CS00002JB13";
"B"
$PN"2"137;
"A"
$PN"1"93;
%"Q_RES"
"1","(-6450,4975)","0","pure_quanta","I56";
;
LOCATION"R269"
$SEC"1"
CDS_SEC"1"
VALUE"0"
CDS_LIB"pure_quanta"
BOM_COST"MEM"
WATTAGE"1/16W"
MATERIAL"CHIP"
TOLERANCE"5%"
PACK_TYPE"0402LF"
PART_NUMBER"CS00002JB13";
"B"
$PN"2"95;
"A"
$PN"1"94;
%"Q_RES"
"1","(-6450,5175)","0","pure_quanta","I57";
;
LOCATION"R141"
$SEC"1"
CDS_SEC"1"
VALUE"0"
PACK_TYPE"0402LF"
TOLERANCE"5%"
MATERIAL"CHIP"
WATTAGE"1/16W"
BOM_COST"MEM"
CDS_LIB"pure_quanta"
PART_NUMBER"CS00002JB13";
"B"
$PN"2"90;
"A"
$PN"1"24;
%"Q_RES"
"1","(-6450,5325)","0","pure_quanta","I58";
;
LOCATION"R189"
$SEC"1"
CDS_SEC"1"
VALUE"0"
CDS_LIB"pure_quanta"
BOM_COST"MEM"
WATTAGE"1/16W"
MATERIAL"CHIP"
TOLERANCE"5%"
PACK_TYPE"0402LF"
PART_NUMBER"CS00002JB13";
"B"
$PN"2"131;
"A"
$PN"1"7;
%"Q_RES"
"1","(-6450,5225)","0","pure_quanta","I59";
;
LOCATION"R137"
$SEC"1"
CDS_SEC"1"
VALUE"0"
BOM_COST"MEM"
CDS_LIB"pure_quanta"
WATTAGE"1/16W"
MATERIAL"CHIP"
TOLERANCE"5%"
PACK_TYPE"0402LF"
PART_NUMBER"CS00002JB13";
"B"
$PN"2"89;
"A"
$PN"1"14;
%"Q_RES"
"1","(-6450,5275)","0","pure_quanta","I60";
;
LOCATION"R231"
$SEC"1"
CDS_SEC"1"
VALUE"0"
CDS_LIB"pure_quanta"
BOM_COST"MEM"
WATTAGE"1/16W"
MATERIAL"CHIP"
TOLERANCE"5%"
PACK_TYPE"0402LF"
PART_NUMBER"CS00002JB13";
"B"
$PN"2"132;
"A"
$PN"1"13;
%"Q_RES"
"1","(-6450,5375)","0","pure_quanta","I61";
;
LOCATION"R188"
$SEC"1"
CDS_SEC"1"
VALUE"0"
CDS_LIB"pure_quanta"
BOM_COST"MEM"
WATTAGE"1/16W"
MATERIAL"CHIP"
TOLERANCE"5%"
PACK_TYPE"0402LF"
PART_NUMBER"CS00002JB13";
"B"
$PN"2"9;
"A"
$PN"1"12;
%"Q_RES"
"1","(-6450,5425)","0","pure_quanta","I62";
;
LOCATION"R239"
$SEC"1"
CDS_SEC"1"
VALUE"0"
CDS_LIB"pure_quanta"
BOM_COST"MEM"
WATTAGE"1/16W"
MATERIAL"CHIP"
TOLERANCE"5%"
PACK_TYPE"0402LF"
PART_NUMBER"CS00002JB13";
"B"
$PN"2"8;
"A"
$PN"1"10;
%"Q_RES"
"1","(-6450,5525)","0","pure_quanta","I63";
;
LOCATION"R243"
$SEC"1"
CDS_SEC"1"
VALUE"0"
BOM_COST"MEM"
CDS_LIB"pure_quanta"
WATTAGE"1/16W"
MATERIAL"CHIP"
TOLERANCE"5%"
PACK_TYPE"0402LF"
PART_NUMBER"CS00002JB13";
"B"
$PN"2"130;
"A"
$PN"1"31;
%"Q_RES"
"1","(-6450,5475)","0","pure_quanta","I64";
;
LOCATION"R190"
$SEC"1"
CDS_SEC"1"
VALUE"0"
CDS_LIB"pure_quanta"
BOM_COST"MEM"
WATTAGE"1/16W"
MATERIAL"CHIP"
TOLERANCE"5%"
PACK_TYPE"0402LF"
PART_NUMBER"CS00002JB13";
"B"
$PN"2"1;
"A"
$PN"1"11;
%"Q_RES"
"1","(-6450,5575)","0","pure_quanta","I65";
;
LOCATION"R246"
$SEC"1"
CDS_SEC"1"
VALUE"0"
BOM_COST"MEM"
CDS_LIB"pure_quanta"
WATTAGE"1/16W"
MATERIAL"CHIP"
TOLERANCE"5%"
PACK_TYPE"0402LF"
PART_NUMBER"CS00002JB13";
"B"
$PN"2"25;
"A"
$PN"1"6;
%"Q_RES"
"1","(-6450,5675)","0","pure_quanta","I66";
;
LOCATION"R236"
$SEC"1"
CDS_SEC"1"
VALUE"0"
BOM_COST"MEM"
CDS_LIB"pure_quanta"
WATTAGE"1/16W"
MATERIAL"CHIP"
TOLERANCE"5%"
PACK_TYPE"0402LF"
PART_NUMBER"CS00002JB13";
"B"
$PN"2"27;
"A"
$PN"1"4;
%"Q_RES"
"1","(-6450,5625)","0","pure_quanta","I67";
;
LOCATION"R245"
$SEC"1"
CDS_SEC"1"
VALUE"0"
CDS_LIB"pure_quanta"
BOM_COST"MEM"
WATTAGE"1/16W"
MATERIAL"CHIP"
TOLERANCE"5%"
PACK_TYPE"0402LF"
PART_NUMBER"CS00002JB13";
"B"
$PN"2"26;
"A"
$PN"1"5;
%"Q_RES"
"1","(-6450,5775)","0","pure_quanta","I68";
;
LOCATION"R187"
$SEC"1"
CDS_SEC"1"
VALUE"0"
BOM_COST"MEM"
CDS_LIB"pure_quanta"
WATTAGE"1/16W"
MATERIAL"CHIP"
TOLERANCE"5%"
PACK_TYPE"0402LF"
PART_NUMBER"CS00002JB13";
"B"
$PN"2"29;
"A"
$PN"1"2;
%"Q_RES"
"1","(-6450,5725)","0","pure_quanta","I69";
;
LOCATION"R237"
$SEC"1"
CDS_SEC"1"
VALUE"0"
BOM_COST"MEM"
CDS_LIB"pure_quanta"
WATTAGE"1/16W"
MATERIAL"CHIP"
TOLERANCE"5%"
PACK_TYPE"0402LF"
PART_NUMBER"CS00002JB13";
"B"
$PN"2"28;
"A"
$PN"1"3;
%"Q_RES"
"1","(-6450,5825)","0","pure_quanta","I70";
;
LOCATION"R235"
$SEC"1"
CDS_SEC"1"
VALUE"0"
CDS_LIB"pure_quanta"
BOM_COST"MEM"
WATTAGE"1/16W"
MATERIAL"CHIP"
TOLERANCE"5%"
PACK_TYPE"0402LF"
PART_NUMBER"CS00002JB13";
"B"
$PN"2"30;
"A"
$PN"1"105;
%"Q_RES"
"1","(-6450,5925)","0","pure_quanta","I71";
;
LOCATION"R238"
$SEC"1"
CDS_SEC"1"
VALUE"0"
BOM_COST"MEM"
CDS_LIB"pure_quanta"
WATTAGE"1/16W"
MATERIAL"CHIP"
TOLERANCE"5%"
PACK_TYPE"0402LF"
PART_NUMBER"CS00002JB13";
"B"
$PN"2"117;
"A"
$PN"1"111;
%"Q_RES"
"1","(-6450,5875)","0","pure_quanta","I72";
;
LOCATION"R244"
$SEC"1"
CDS_SEC"1"
VALUE"0"
CDS_LIB"pure_quanta"
BOM_COST"MEM"
WATTAGE"1/16W"
MATERIAL"CHIP"
TOLERANCE"5%"
PACK_TYPE"0402LF"
PART_NUMBER"CS00002JB13";
"B"
$PN"2"133;
"A"
$PN"1"112;
%"Q_RES"
"1","(-6450,5975)","0","pure_quanta","I73";
;
LOCATION"R267"
$SEC"1"
CDS_SEC"1"
VALUE"33"
BOM_COST"MEM"
WATTAGE"1/16W"
MATERIAL"CHIP"
TOLERANCE"5%"
PACK_TYPE"0402LF"
CDS_LIB"pure_quanta"
PART_NUMBER"CS03302JB10";
"B"
$PN"2"134;
"A"
$PN"1"104;
%"Q_RES"
"1","(-6450,6075)","0","pure_quanta","I74";
;
LOCATION"R205"
$SEC"1"
CDS_SEC"1"
VALUE"0"
CDS_LIB"pure_quanta"
BOM_COST"MEM"
WATTAGE"1/16W"
MATERIAL"CHIP"
TOLERANCE"5%"
PACK_TYPE"0402LF"
PART_NUMBER"CS00002JB13";
"B"
$PN"2"116;
"A"
$PN"1"103;
%"Q_RES"
"1","(-6450,6025)","0","pure_quanta","I75";
;
LOCATION"R234"
$SEC"1"
CDS_SEC"1"
VALUE"0"
CDS_LIB"pure_quanta"
BOM_COST"MEM"
WATTAGE"1/16W"
MATERIAL"CHIP"
TOLERANCE"5%"
PACK_TYPE"0402LF"
PART_NUMBER"CS00002JB13";
"B"
$PN"2"135;
"A"
$PN"1"102;
%"Q_RES"
"1","(-6450,6125)","0","pure_quanta","I77";
;
LOCATION"R204"
$SEC"1"
CDS_SEC"1"
VALUE"0"
CDS_LIB"pure_quanta"
BOM_COST"MEM"
WATTAGE"1/16W"
MATERIAL"CHIP"
TOLERANCE"5%"
PACK_TYPE"0402LF"
PART_NUMBER"CS00002JB13";
"B"
$PN"2"115;
"A"
$PN"1"136;
%"UNIVERSAL_POWER"
"1","(-3675,1700)","2","pure_quanta_power","I78";
;
HDL_POWER"P3V3_AUX"
CDS_LIB"pure_quanta_power";
"A"34;
%"VCC_CORE"
"1","(-3375,1850)","0","pure_quanta_power","I79";
;
HDL_POWER"P1V8_AUX"
CDS_LIB"pure_quanta_power";
"A"35;
%"Q_RES"
"1","(-3250,3525)","2","pure_quanta","I80";
;
LOCATION"R185"
$SEC"1"
CDS_SEC"1"
VALUE"0"
BOM_COST"MEM"
CDS_LIB"pure_quanta"
WATTAGE"1/16W"
MATERIAL"CHIP"
TOLERANCE"5%"
PACK_TYPE"0402LF"
PART_NUMBER"CS00002JB13";
"B"
$PN"2"49;
"A"
$PN"1"51;
%"Q_RES"
"1","(-3250,3475)","2","pure_quanta","I81";
;
LOCATION"R959"
$SEC"1"
CDS_SEC"1"
VALUE"33"
BOM_COST"MEM"
CDS_LIB"pure_quanta"
WATTAGE"1/16W"
MATERIAL"CHIP"
TOLERANCE"5%"
PACK_TYPE"0402LF"
PART_NUMBER"CS03302JB10";
"B"
$PN"2"53;
"A"
$PN"1"50;
%"Q_RES"
"1","(-3250,3575)","2","pure_quanta","I82";
;
LOCATION"R183"
$SEC"1"
CDS_SEC"1"
VALUE"0"
PACK_TYPE"0402LF"
TOLERANCE"5%"
MATERIAL"CHIP"
WATTAGE"1/16W"
CDS_LIB"pure_quanta"
BOM_COST"MEM"
PART_NUMBER"CS00002JB13";
"B"
$PN"2"48;
"A"
$PN"1"42;
%"Q_RES"
"1","(-3250,3675)","2","pure_quanta","I83";
;
LOCATION"R6054"
$SEC"1"
CDS_SEC"1"
VALUE"0"
PACK_TYPE"0402LF"
TOLERANCE"5%"
MATERIAL"CHIP"
WATTAGE"1/16W"
CDS_LIB"pure_quanta"
BOM_COST"MEM"
PART_NUMBER"CS00002JB13";
"B"
$PN"2"47;
"A"
$PN"1"43;
%"Q_RES"
"1","(-3250,3725)","2","pure_quanta","I84";
;
LOCATION"R275"
$SEC"1"
CDS_SEC"1"
VALUE"33"
BOM_COST"MEM"
CDS_LIB"pure_quanta"
WATTAGE"1/16W"
MATERIAL"CHIP"
TOLERANCE"5%"
PACK_TYPE"0402LF"
PART_NUMBER"CS03302JB10";
"B"
$PN"2"46;
"A"
$PN"1"40;
%"Q_RES"
"1","(-3250,3825)","2","pure_quanta","I85";
;
LOCATION"R6053"
$SEC"1"
CDS_SEC"1"
VALUE"0"
CDS_LIB"pure_quanta"
BOM_COST"MEM"
WATTAGE"1/16W"
MATERIAL"CHIP"
TOLERANCE"5%"
PACK_TYPE"0402LF"
PART_NUMBER"CS00002JB13";
"B"
$PN"2"54;
"A"
$PN"1"57;
%"Q_RES"
"1","(-3250,3925)","2","pure_quanta","I86";
;
LOCATION"R958"
$SEC"1"
CDS_SEC"1"
VALUE"33"
BOM_COST"MEM"
CDS_LIB"pure_quanta"
WATTAGE"1/16W"
MATERIAL"CHIP"
TOLERANCE"5%"
PACK_TYPE"0402LF"
PART_NUMBER"CS03302JB10";
"B"
$PN"2"55;
"A"
$PN"1"56;
%"UNIVERSAL_POWER"
"1","(-1575,1175)","2","pure_quanta_power","I97";
;
HDL_POWER"P3V3_AUX"
CDS_LIB"pure_quanta_power";
"A"36;
%"VCC_CORE"
"1","(-1550,1900)","0","pure_quanta_power","I98";
;
HDL_POWER"P1V8_AUX"
CDS_LIB"pure_quanta_power";
"A"37;
%"Q_RES"
"1","(-3200,4425)","0","pure_quanta","I99";
;
LOCATION"R6052"
$SEC"1"
CDS_SEC"1"
VALUE"0"
BOM_COST"MEM"
CDS_LIB"pure_quanta"
WATTAGE"1/16W"
MATERIAL"CHIP"
TOLERANCE"5%"
PACK_TYPE"0402LF"
PART_NUMBER"CS00002JB13";
"B"
$PN"2"88;
"A"
$PN"1"76;
END.
